FILE_TYPE = CONNECTIVITY;
{Allegro Design Entry HDL 16.6-p007 (v16-6-112F) 10/10/2012}
"PAGE_NUMBER" = 197;
0"NC";
1"P12V_NVDIMM_ABC\g";
2"GND\g";
3"GND\g";
4"P12V_NVDIMM_DEF\g";
5"GND\g";
6"P12V_NVDIMM_GHJ\g";
7"GND\g";
8"P12V_NVDIMM_KLM\g";
9"P12V_STBY\g";
10"P12V_STBY\g";
11"P12V_STBY\g";
12"P12V_STBY\g";
13"GND\g";
14"P12V_NVDIMM_ABC\g";
15"GND\g";
16"P12V_NVDIMM_ABC\g";
17"GND\g";
18"GND\g";
19"P12V_NVDIMM_DEF\g";
20"GND\g";
21"P12V_NVDIMM_DEF\g";
22"GND\g";
23"P12V_NVDIMM_ABC\g";
24"P12V_NVDIMM_DEF\g";
25"GND\g";
26"P12V_NVDIMM_GHJ\g";
27"GND\g";
28"P12V_NVDIMM_GHJ\g";
29"GND\g";
30"P12V_NVDIMM_GHJ\g";
31"GND\g";
32"P12V_NVDIMM_KLM\g";
33"GND\g";
34"P12V_NVDIMM_KLM\g";
35"GND\g";
36"P12V_NVDIMM_KLM\g";
37"VR_PVDDQ_GHJ_AIINSEN_R";
38"VR_PVDDQ_DEF_AIINSEN_R";
39"VR_PVDDQ_DEF_AIINSEN";
40"VR_PVDDQ_GHJ_AIINSEN";
41"VR_PVDDQ_ABC_AIINSEN_R";
42"VR_PVDDQ_ABC_AIINSEN";
43"VR_PVDDQ_KLM_AIINSEN_R";
44"VR_PVDDQ_KLM_AIINSEN";
%"P12V_NVDIMM_ABC"
"1","(-4875,4925)","0","mstr_symbols","I101";
;
HDL_POWER"P12V_NVDIMM_ABC"
BODY_TYPE"PLUMBING"
CDS_LIB"mstr_symbols"
VOLTAGE"12.0";
"G\NAC"1;
%"GND"
"1","(-3250,4150)","0","mstr_symbols","I103";
;
HDL_POWER"GND"
BODY_TYPE"PLUMBING"
CDS_LIB"mstr_symbols"
SIZE"1B"
VOLTAGE"0.0V";
"A\NAC"2;
%"RES"
"1","(-2775,4475)","0","mstr_discrete","I110";
;
CDS_SEC"1"
ROOM"PVDDQ_ABC_PWR_VR"
CDS_LOCATION"R4F1"
SEC"1"
BOM_COST"PVDDQ_ABC_VR"
CDS_LIB"mstr_discrete"
SEC_TYPE"0402"
WATTAGE"1/16W"
MATERIAL"CHIP"
PACK_TYPE"0402"
TOLERANCE"5%"
VALUE"0.0"
PART_NUMBER"G21497-005"
LOCATION"R4F1";
"B"
$PN"2"42;
"A"
$PN"1"41;
%"RES"
"1","(-2775,3025)","0","mstr_discrete","I113";
;
CDS_SEC"1"
ROOM"PVDDQ_DEF_PWR_VR"
CDS_LOCATION"R4B11"
SEC"1"
BOM_COST"PVDDQ_DEF_VR"
CDS_LIB"mstr_discrete"
SEC_TYPE"0402"
WATTAGE"1/16W"
MATERIAL"CHIP"
PACK_TYPE"0402"
TOLERANCE"5%"
VALUE"0.0"
PART_NUMBER"G21497-005"
LOCATION"R4B11";
"B"
$PN"2"39;
"A"
$PN"1"38;
%"GND"
"1","(-3250,2700)","0","mstr_symbols","I114";
;
HDL_POWER"GND"
BODY_TYPE"PLUMBING"
SIZE"1B"
CDS_LIB"mstr_symbols"
VOLTAGE"0.0V";
"A\NAC"3;
%"MAX9634"
"1","(-3800,2975)","0","mstr_vreg","I120";
;
CDS_SEC"1"
ROOM"PVDDQ_DEF_PWR_VR"
CDS_LOCATION"U4B1"
SEC"1"
CDS_LIB"mstr_vreg"
BOM_COST"PVDDQ_DEF_VR"
SEC_TYPE"SOT"
PACK_TYPE"SOT"
MATERIAL"IC"
PART_NUMBER"H35789-001"
LOCATION"U4B1";
"GND<0>"
$PN"2"3;
"GND<1>"
$PN"1"3;
"OUT"
$PN"3"38;
"RSP"
$PN"5"10;
"RSN"
$PN"4"4;
%"RES"
"1","(-4575,3300)","0","mstr_discrete","I121";
;
CDS_SEC"1"
ROOM"PVDDQ_DEF_PWR_VR"
CDS_LOCATION"R4B12"
SEC"1"
CDS_LIB"mstr_discrete"
BOM_COST"PVDDQ_DEF_VR"
SEC_TYPE"1206"
WATTAGE"1W"
MATERIAL"CHIP"
PACK_TYPE"1206"
TOLERANCE"1%"
VALUE"0.002"
PART_NUMBER"G52199-004"
LOCATION"R4B12";
"B"
$PN"2"10;
"A"
$PN"1"4;
%"P12V_NVDIMM_DEF"
"1","(-4875,3475)","0","mstr_symbols","I122";
;
HDL_POWER"P12V_NVDIMM_DEF"
BODY_TYPE"PLUMBING"
CDS_LIB"mstr_symbols"
VOLTAGE"12.0";
"G\NAC"4;
%"RES"
"1","(-2775,1600)","0","mstr_discrete","I126";
;
CDS_SEC"1"
ROOM"PVDDQ_GHJ_PWR_VR"
CDS_LOCATION"R9T4"
SEC"1"
CDS_LIB"mstr_discrete"
BOM_COST"PVDDQ_GHJ_VR"
SEC_TYPE"0402"
WATTAGE"1/16W"
MATERIAL"CHIP"
PACK_TYPE"0402"
TOLERANCE"5%"
VALUE"0.0"
PART_NUMBER"G21497-005"
LOCATION"R9T4";
"B"
$PN"2"40;
"A"
$PN"1"37;
%"GND"
"1","(-3250,1275)","0","mstr_symbols","I129";
;
HDL_POWER"GND"
BODY_TYPE"PLUMBING"
SIZE"1B"
CDS_LIB"mstr_symbols"
VOLTAGE"0.0V";
"A\NAC"5;
%"RES"
"1","(-4575,1875)","0","mstr_discrete","I131";
;
CDS_SEC"1"
ROOM"PVDDQ_GHJ_PWR_VR"
CDS_LOCATION"R1F3"
SEC"1"
BOM_COST"PVDDQ_GHJ_VR"
CDS_LIB"mstr_discrete"
SEC_TYPE"1206"
WATTAGE"1W"
MATERIAL"CHIP"
PACK_TYPE"1206"
TOLERANCE"1%"
VALUE"0.002"
PART_NUMBER"G52199-004"
LOCATION"R1F3";
"B"
$PN"2"12;
"A"
$PN"1"6;
%"P12V_NVDIMM_GHJ"
"1","(-4875,2050)","0","mstr_symbols","I132";
;
HDL_POWER"P12V_NVDIMM_GHJ"
BODY_TYPE"PLUMBING"
CDS_LIB"mstr_symbols"
VOLTAGE"12.0";
"G\NAC"6;
%"MAX9634"
"1","(-3800,1550)","0","mstr_vreg","I133";
;
CDS_SEC"1"
ROOM"PVDDQ_GHJ_PWR_VR"
CDS_LOCATION"U1F1"
SEC"1"
CDS_LIB"mstr_vreg"
BOM_COST"PVDDQ_GHJ_VR"
SEC_TYPE"SOT"
PACK_TYPE"SOT"
MATERIAL"IC"
PART_NUMBER"H35789-001"
LOCATION"U1F1";
"GND<0>"
$PN"2"5;
"GND<1>"
$PN"1"5;
"OUT"
$PN"3"37;
"RSP"
$PN"5"12;
"RSN"
$PN"4"6;
%"RES"
"1","(1050,4475)","0","mstr_discrete","I137";
;
CDS_SEC"1"
ROOM"PVDDQ_KLM_PWR_VR"
CDS_LOCATION"R1B14"
SEC"1"
CDS_LIB"mstr_discrete"
BOM_COST"PVDDQ_KLM_VR"
SEC_TYPE"0402"
WATTAGE"1/16W"
MATERIAL"CHIP"
PACK_TYPE"0402"
TOLERANCE"5%"
VALUE"0.0"
PART_NUMBER"G21497-005"
LOCATION"R1B14";
"B"
$PN"2"44;
"A"
$PN"1"43;
%"GND"
"1","(575,4150)","0","mstr_symbols","I140";
;
HDL_POWER"GND"
BODY_TYPE"PLUMBING"
CDS_LIB"mstr_symbols"
SIZE"1B"
VOLTAGE"0.0V";
"A\NAC"7;
%"RES"
"1","(-750,4750)","0","mstr_discrete","I142";
;
CDS_SEC"1"
ROOM"PVDDQ_KLM_PWR_VR"
CDS_LOCATION"R9M4"
SEC"1"
CDS_LIB"mstr_discrete"
BOM_COST"PVDDQ_KLM_VR"
SEC_TYPE"1206"
WATTAGE"1W"
MATERIAL"CHIP"
PACK_TYPE"1206"
TOLERANCE"1%"
VALUE"0.002"
PART_NUMBER"G52199-004"
LOCATION"R9M4";
"B"
$PN"2"11;
"A"
$PN"1"8;
%"P12V_NVDIMM_KLM"
"1","(-1050,4925)","0","mstr_symbols","I143";
;
HDL_POWER"P12V_NVDIMM_KLM"
BODY_TYPE"PLUMBING"
CDS_LIB"mstr_symbols"
VOLTAGE"12.0";
"G\NAC"8;
%"MAX9634"
"1","(25,4425)","0","mstr_vreg","I144";
;
CDS_SEC"1"
ROOM"PVDDQ_KLM_PWR_VR"
CDS_LOCATION"U1B1"
SEC"1"
CDS_LIB"mstr_vreg"
BOM_COST"PVDDQ_KLM_VR"
SEC_TYPE"SOT"
PACK_TYPE"SOT"
MATERIAL"IC"
PART_NUMBER"H35789-001"
LOCATION"U1B1";
"GND<0>"
$PN"2"7;
"GND<1>"
$PN"1"7;
"OUT"
$PN"3"43;
"RSP"
$PN"5"11;
"RSN"
$PN"4"8;
%"P12V_STBY"
"1","(-4200,4925)","0","mstr_symbols","I145";
;
HDL_POWER"P12V_STBY"
BODY_TYPE"PLUMBING"
CDS_LIB"mstr_symbols"
SIZE"1B"
VOLTAGE"12.0V";
"G\NAC"9;
%"P12V_STBY"
"1","(-4200,3475)","0","mstr_symbols","I146";
;
HDL_POWER"P12V_STBY"
BODY_TYPE"PLUMBING"
CDS_LIB"mstr_symbols"
SIZE"1B"
VOLTAGE"12.0V";
"G\NAC"10;
%"P12V_STBY"
"1","(-375,4925)","0","mstr_symbols","I147";
;
HDL_POWER"P12V_STBY"
BODY_TYPE"PLUMBING"
CDS_LIB"mstr_symbols"
SIZE"1B"
VOLTAGE"12.0V";
"G\NAC"11;
%"P12V_STBY"
"1","(-4200,2050)","0","mstr_symbols","I148";
;
HDL_POWER"P12V_STBY"
BODY_TYPE"PLUMBING"
CDS_LIB"mstr_symbols"
SIZE"1B"
VOLTAGE"12.0V";
"G\NAC"12;
%"GND"
"1","(-825,1425)","0","mstr_symbols","I51";
;
HDL_POWER"GND"
BODY_TYPE"PLUMBING"
CDS_LIB"mstr_symbols"
SIZE"1B"
VOLTAGE"0.0V";
"A\NAC"13;
%"CAP"
"1","(-825,1625)","0","mstr_discrete","I52";
;
ROOM"PVDDQ_ABC_PWR_VR"
CDS_LOCATION"C6U18"
$SEC"1"
CDS_SEC"1"
CDS_LIB"mstr_discrete"
MATERIAL"X7R"
VOLTAGE"16V"
PACK_TYPE"0805"
TOLERANCE"10%"
VALUE"10UF"
PART_NUMBER"G10601-001"
LOCATION"C6U18";
"A"
$PN"1"14;
"B"
$PN"2"13;
%"P12V_NVDIMM_ABC"
"1","(-825,1800)","0","mstr_symbols","I53";
;
HDL_POWER"P12V_NVDIMM_ABC"
BODY_TYPE"PLUMBING"
CDS_LIB"mstr_symbols"
VOLTAGE"12.0";
"G\NAC"14;
%"CAP"
"1","(-825,2200)","0","mstr_discrete","I54";
;
ROOM"PVDDQ_ABC_PWR_VR"
CDS_LOCATION"C6T2"
$SEC"1"
CDS_SEC"1"
CDS_LIB"mstr_discrete"
MATERIAL"X7R"
VOLTAGE"16V"
PACK_TYPE"0805"
TOLERANCE"10%"
VALUE"10UF"
PART_NUMBER"G10601-001"
LOCATION"C6T2";
"A"
$PN"1"16;
"B"
$PN"2"15;
%"GND"
"1","(-825,2000)","0","mstr_symbols","I55";
;
HDL_POWER"GND"
BODY_TYPE"PLUMBING"
CDS_LIB"mstr_symbols"
SIZE"1B"
VOLTAGE"0.0V";
"A\NAC"15;
%"P12V_NVDIMM_ABC"
"1","(-825,2375)","0","mstr_symbols","I56";
;
HDL_POWER"P12V_NVDIMM_ABC"
BODY_TYPE"PLUMBING"
CDS_LIB"mstr_symbols"
VOLTAGE"12.0";
"G\NAC"16;
%"GND"
"1","(-825,2650)","0","mstr_symbols","I57";
;
HDL_POWER"GND"
BODY_TYPE"PLUMBING"
CDS_LIB"mstr_symbols"
SIZE"1B"
VOLTAGE"0.0V";
"A\NAC"17;
%"GND"
"1","(25,1425)","0","mstr_symbols","I58";
;
HDL_POWER"GND"
BODY_TYPE"PLUMBING"
SIZE"1B"
CDS_LIB"mstr_symbols"
VOLTAGE"0.0V";
"A\NAC"18;
%"CAP"
"1","(25,1625)","0","mstr_discrete","I59";
;
ROOM"PVDDQ_DEF_PWR_VR"
CDS_LOCATION"C4B11"
$SEC"1"
CDS_SEC"1"
CDS_LIB"mstr_discrete"
MATERIAL"X7R"
VOLTAGE"16V"
PACK_TYPE"0805"
TOLERANCE"10%"
VALUE"10UF"
PART_NUMBER"G10601-001"
LOCATION"C4B11";
"A"
$PN"1"19;
"B"
$PN"2"18;
%"P12V_NVDIMM_DEF"
"1","(25,1800)","0","mstr_symbols","I60";
;
HDL_POWER"P12V_NVDIMM_DEF"
BODY_TYPE"PLUMBING"
CDS_LIB"mstr_symbols"
VOLTAGE"12.0";
"G\NAC"19;
%"GND"
"1","(25,2000)","0","mstr_symbols","I61";
;
HDL_POWER"GND"
BODY_TYPE"PLUMBING"
SIZE"1B"
CDS_LIB"mstr_symbols"
VOLTAGE"0.0V";
"A\NAC"20;
%"CAP"
"1","(25,2200)","0","mstr_discrete","I62";
;
ROOM"PVDDQ_DEF_PWR_VR"
CDS_LOCATION"C4A4"
$SEC"1"
CDS_SEC"1"
CDS_LIB"mstr_discrete"
MATERIAL"X7R"
VOLTAGE"16V"
PACK_TYPE"0805"
TOLERANCE"10%"
VALUE"10UF"
PART_NUMBER"G10601-001"
LOCATION"C4A4";
"A"
$PN"1"21;
"B"
$PN"2"20;
%"P12V_NVDIMM_DEF"
"1","(25,2375)","0","mstr_symbols","I63";
;
HDL_POWER"P12V_NVDIMM_DEF"
BODY_TYPE"PLUMBING"
CDS_LIB"mstr_symbols"
VOLTAGE"12.0";
"G\NAC"21;
%"GND"
"1","(25,2650)","0","mstr_symbols","I64";
;
HDL_POWER"GND"
BODY_TYPE"PLUMBING"
CDS_LIB"mstr_symbols"
SIZE"1B"
VOLTAGE"0.0V";
"A\NAC"22;
%"CAP"
"1","(-825,2850)","0","mstr_discrete","I65";
;
ROOM"PVDDQ_ABC_PWR_VR"
CDS_LOCATION"C6U10"
$SEC"1"
CDS_SEC"1"
CDS_LIB"mstr_discrete"
MATERIAL"X7R"
VOLTAGE"16V"
PACK_TYPE"0805"
TOLERANCE"10%"
VALUE"10UF"
PART_NUMBER"G10601-001"
LOCATION"C6U10";
"A"
$PN"1"23;
"B"
$PN"2"17;
%"P12V_NVDIMM_ABC"
"1","(-825,3025)","0","mstr_symbols","I66";
;
HDL_POWER"P12V_NVDIMM_ABC"
BODY_TYPE"PLUMBING"
CDS_LIB"mstr_symbols"
VOLTAGE"12.0";
"G\NAC"23;
%"CAP"
"1","(25,2850)","0","mstr_discrete","I67";
;
ROOM"PVDDQ_DEF_PWR_VR"
CDS_LOCATION"C4A17"
$SEC"1"
CDS_SEC"1"
CDS_LIB"mstr_discrete"
MATERIAL"X7R"
VOLTAGE"16V"
PACK_TYPE"0805"
TOLERANCE"10%"
VALUE"10UF"
PART_NUMBER"G10601-001"
LOCATION"C4A17";
"A"
$PN"1"24;
"B"
$PN"2"22;
%"P12V_NVDIMM_DEF"
"1","(25,3025)","0","mstr_symbols","I68";
;
HDL_POWER"P12V_NVDIMM_DEF"
BODY_TYPE"PLUMBING"
CDS_LIB"mstr_symbols"
VOLTAGE"12.0";
"G\NAC"24;
%"GND"
"1","(850,1450)","0","mstr_symbols","I69";
;
HDL_POWER"GND"
BODY_TYPE"PLUMBING"
CDS_LIB"mstr_symbols"
SIZE"1B"
VOLTAGE"0.0V";
"A\NAC"25;
%"CAP"
"1","(850,1625)","0","mstr_discrete","I70";
;
ROOM"PVDDQ_GHJ_PWR_VR"
CDS_LOCATION"C9T8"
$SEC"1"
CDS_SEC"1"
CDS_LIB"mstr_discrete"
MATERIAL"X7R"
VOLTAGE"16V"
PACK_TYPE"0805"
TOLERANCE"10%"
VALUE"10UF"
PART_NUMBER"G10601-001"
LOCATION"C9T8";
"A"
$PN"1"26;
"B"
$PN"2"25;
%"P12V_NVDIMM_GHJ"
"1","(850,1800)","0","mstr_symbols","I71";
;
HDL_POWER"P12V_NVDIMM_GHJ"
BODY_TYPE"PLUMBING"
CDS_LIB"mstr_symbols"
VOLTAGE"12.0";
"G\NAC"26;
%"GND"
"1","(850,2025)","0","mstr_symbols","I72";
;
HDL_POWER"GND"
BODY_TYPE"PLUMBING"
SIZE"1B"
CDS_LIB"mstr_symbols"
VOLTAGE"0.0V";
"A\NAC"27;
%"CAP"
"1","(850,2200)","0","mstr_discrete","I73";
;
ROOM"PVDDQ_GHJ_PWR_VR"
CDS_LOCATION"C9U11"
$SEC"1"
CDS_SEC"1"
CDS_LIB"mstr_discrete"
MATERIAL"X7R"
VOLTAGE"16V"
PACK_TYPE"0805"
TOLERANCE"10%"
VALUE"10UF"
PART_NUMBER"G10601-001"
LOCATION"C9U11";
"A"
$PN"1"28;
"B"
$PN"2"27;
%"P12V_NVDIMM_GHJ"
"1","(850,2375)","0","mstr_symbols","I74";
;
HDL_POWER"P12V_NVDIMM_GHJ"
BODY_TYPE"PLUMBING"
CDS_LIB"mstr_symbols"
VOLTAGE"12.0";
"G\NAC"28;
%"GND"
"1","(850,2675)","0","mstr_symbols","I75";
;
HDL_POWER"GND"
BODY_TYPE"PLUMBING"
CDS_LIB"mstr_symbols"
SIZE"1B"
VOLTAGE"0.0V";
"A\NAC"29;
%"CAP"
"1","(850,2850)","0","mstr_discrete","I76";
;
ROOM"PVDDQ_GHJ_PWR_VR"
CDS_LOCATION"C9U8"
$SEC"1"
CDS_SEC"1"
CDS_LIB"mstr_discrete"
MATERIAL"X7R"
VOLTAGE"16V"
PACK_TYPE"0805"
TOLERANCE"10%"
VALUE"10UF"
PART_NUMBER"G10601-001"
LOCATION"C9U8";
"A"
$PN"1"30;
"B"
$PN"2"29;
%"P12V_NVDIMM_GHJ"
"1","(850,3025)","0","mstr_symbols","I77";
;
HDL_POWER"P12V_NVDIMM_GHJ"
BODY_TYPE"PLUMBING"
CDS_LIB"mstr_symbols"
VOLTAGE"12.0";
"G\NAC"30;
%"GND"
"1","(1700,1425)","0","mstr_symbols","I78";
;
HDL_POWER"GND"
BODY_TYPE"PLUMBING"
SIZE"1B"
CDS_LIB"mstr_symbols"
VOLTAGE"0.0V";
"A\NAC"31;
%"CAP"
"1","(1700,1625)","0","mstr_discrete","I79";
;
ROOM"PVDDQ_KLM_PWR_VR"
CDS_LOCATION"C1A4"
$SEC"1"
CDS_SEC"1"
CDS_LIB"mstr_discrete"
MATERIAL"X7R"
VOLTAGE"16V"
PACK_TYPE"0805"
TOLERANCE"10%"
VALUE"10UF"
PART_NUMBER"G10601-001"
LOCATION"C1A4";
"A"
$PN"1"32;
"B"
$PN"2"31;
%"P12V_NVDIMM_KLM"
"1","(1700,1800)","0","mstr_symbols","I80";
;
HDL_POWER"P12V_NVDIMM_KLM"
BODY_TYPE"PLUMBING"
CDS_LIB"mstr_symbols"
VOLTAGE"12.0";
"G\NAC"32;
%"GND"
"1","(1700,2000)","0","mstr_symbols","I81";
;
HDL_POWER"GND"
BODY_TYPE"PLUMBING"
SIZE"1B"
CDS_LIB"mstr_symbols"
VOLTAGE"0.0V";
"A\NAC"33;
%"CAP"
"1","(1700,2200)","0","mstr_discrete","I82";
;
ROOM"PVDDQ_KLM_PWR_VR"
CDS_LOCATION"C1B7"
$SEC"1"
CDS_SEC"1"
CDS_LIB"mstr_discrete"
MATERIAL"X7R"
VOLTAGE"16V"
PACK_TYPE"0805"
TOLERANCE"10%"
VALUE"10UF"
PART_NUMBER"G10601-001"
LOCATION"C1B7";
"A"
$PN"1"34;
"B"
$PN"2"33;
%"P12V_NVDIMM_KLM"
"1","(1700,2375)","0","mstr_symbols","I83";
;
HDL_POWER"P12V_NVDIMM_KLM"
BODY_TYPE"PLUMBING"
CDS_LIB"mstr_symbols"
VOLTAGE"12.0";
"G\NAC"34;
%"GND"
"1","(1700,2650)","0","mstr_symbols","I84";
;
HDL_POWER"GND"
BODY_TYPE"PLUMBING"
SIZE"1B"
CDS_LIB"mstr_symbols"
VOLTAGE"0.0V";
"A\NAC"35;
%"CAP"
"1","(1700,2850)","0","mstr_discrete","I85";
;
ROOM"PVDDQ_KLM_PWR_VR"
CDS_LOCATION"C1A16"
$SEC"1"
CDS_SEC"1"
CDS_LIB"mstr_discrete"
MATERIAL"X7R"
VOLTAGE"16V"
PACK_TYPE"0805"
TOLERANCE"10%"
VALUE"10UF"
PART_NUMBER"G10601-001"
LOCATION"C1A16";
"A"
$PN"1"36;
"B"
$PN"2"35;
%"P12V_NVDIMM_KLM"
"1","(1700,3025)","0","mstr_symbols","I86";
;
HDL_POWER"P12V_NVDIMM_KLM"
BODY_TYPE"PLUMBING"
CDS_LIB"mstr_symbols"
VOLTAGE"12.0";
"G\NAC"36;
%"MAX9634"
"1","(-3800,4425)","0","mstr_vreg","I97";
;
CDS_SEC"1"
ROOM"PVDDQ_ABC_PWR_VR"
CDS_LOCATION"U4F1"
SEC"1"
CDS_LIB"mstr_vreg"
BOM_COST"PVDDQ_ABC_VR"
SEC_TYPE"SOT"
PACK_TYPE"SOT"
MATERIAL"IC"
PART_NUMBER"H35789-001"
LOCATION"U4F1";
"GND<0>"
$PN"2"2;
"GND<1>"
$PN"1"2;
"OUT"
$PN"3"41;
"RSP"
$PN"5"9;
"RSN"
$PN"4"1;
%"RES"
"1","(-4575,4750)","0","mstr_discrete","I99";
;
CDS_SEC"1"
ROOM"PVDDQ_ABC_PWR_VR"
CDS_LOCATION"R4F2"
SEC"1"
CDS_LIB"mstr_discrete"
BOM_COST"PVDDQ_ABC_VR"
SEC_TYPE"1206"
WATTAGE"1W"
MATERIAL"CHIP"
PACK_TYPE"1206"
TOLERANCE"1%"
VALUE"0.002"
PART_NUMBER"G52199-004"
LOCATION"R4F2";
"B"
$PN"2"9;
"A"
$PN"1"1;
END.
